(kicad_pcb
	(version 20260206)
	(generator "pcbnew")
	(generator_version "10.0")
	(general
		(thickness 1.6)
		(legacy_teardrops no)
	)
	(paper "A4")
	(title_block
		(title "01162023_DA0F0TEBIF0_F0T_Expander_BD_F_brd_V02_OCP.brd")
		(comment 1 "Grand Teton / footprints 3301-3307 of 9728")
	)
	(layers
		(0 "F.Cu" signal "TOP")
		(4 "In1.Cu" signal "GND")
		(6 "In2.Cu" signal "VCC")
		(8 "In3.Cu" signal "VCC1")
		(10 "In4.Cu" signal "GND1")
		(12 "In5.Cu" signal "IN1")
		(14 "In6.Cu" signal "GND2")
		(16 "In7.Cu" signal "IN2")
		(18 "In8.Cu" signal "GND3")
		(20 "In9.Cu" signal "IN3")
		(22 "In10.Cu" signal "GND4")
		(24 "In11.Cu" signal "IN4")
		(26 "In12.Cu" signal "GND5")
		(28 "In13.Cu" signal "IN5")
		(30 "In14.Cu" signal "GND6")
		(32 "In15.Cu" signal "IN6")
		(34 "In16.Cu" signal "GND7")
		(2 "B.Cu" signal "BOTTOM")
		(9 "F.Adhes" user "F.Adhesive")
		(11 "B.Adhes" user "B.Adhesive")
		(13 "F.Paste" user "Package Geometry/Pastemask Top")
		(15 "B.Paste" user "Package Geometry/Pastemask Bottom")
		(5 "F.SilkS" user "Ref Des/Silkscreen Top")
		(7 "B.SilkS" user "Ref Des/Silkscreen Bottom")
		(1 "F.Mask" user "Board Geometry/Soldermask Top")
		(3 "B.Mask" user "Board Geometry/Soldermask Bottom")
		(17 "Dwgs.User" user "User.Drawings")
		(19 "Cmts.User" user "User.Comments")
		(21 "Eco1.User" user "User.Eco1")
		(23 "Eco2.User" user "User.Eco2")
		(25 "Edge.Cuts" user "Board Geometry/Outline")
		(27 "Margin" user)
		(31 "F.CrtYd" user "Package Geometry/Place Bound Top")
		(29 "B.CrtYd" user "Package Geometry/Place Bound Bottom")
		(35 "F.Fab" user "Ref Des/Assembly Top")
		(33 "B.Fab" user "Ref Des/Assembly Bottom")
	)
	(footprint ""
		(layer "F.Cu")
		(at 234.982512 -29.875734)
		(property "Reference" "PU127"
			(at -3.115564 -1.472438 90)
			(unlocked yes)
			(layer "F.SilkS")
			(effects
				(font
					(size 0.7874 0.5842)
					(thickness 0.1524)
				)
			)
		)
		(property "Value" ""
			(at 0 0 0)
			(layer "F.Fab")
			(effects
				(font
					(size 1.27 1.27)
				)
			)
		)
		(duplicate_pad_numbers_are_jumpers no)
		(fp_line
			(start -1.239774 -1.495298)
			(end 1.239774 -1.495298)
			(stroke
				(width 0.1524)
				(type default)
			)
			(layer "F.SilkS")
		)
		(fp_line
			(start -1.239774 1.495298)
			(end -1.239774 -1.495298)
			(stroke
				(width 0.1524)
				(type default)
			)
			(layer "F.SilkS")
		)
		(fp_line
			(start 1.239774 -1.495298)
			(end 1.239774 1.495298)
			(stroke
				(width 0.1524)
				(type default)
			)
			(layer "F.SilkS")
		)
		(fp_line
			(start 1.239774 1.495298)
			(end -1.239774 1.495298)
			(stroke
				(width 0.1524)
				(type default)
			)
			(layer "F.SilkS")
		)
		(fp_poly
			(pts
				(xy -1.93167 -1.763014) (xy -2.649982 -1.044702) (xy -1.57226 -0.685292)
			)
			(stroke
				(width 0)
				(type default)
			)
			(fill yes)
			(layer "F.SilkS")
		)
		(fp_line
			(start -0.8001 -1.050036)
			(end 0.8001 -1.050036)
			(stroke
				(width 0.1)
				(type default)
			)
			(layer "F.Fab")
		)
		(fp_line
			(start -0.8001 1.050036)
			(end -0.8001 -1.050036)
			(stroke
				(width 0.1)
				(type default)
			)
			(layer "F.Fab")
		)
		(fp_line
			(start 0.8001 -1.050036)
			(end 0.8001 1.050036)
			(stroke
				(width 0.1)
				(type default)
			)
			(layer "F.Fab")
		)
		(fp_line
			(start 0.8001 1.050036)
			(end -0.8001 1.050036)
			(stroke
				(width 0.1)
				(type default)
			)
			(layer "F.Fab")
		)
		(fp_poly
			(pts
				(xy -2.458974 -0.508) (xy -2.458974 0.508) (xy -1.442974 0)
			)
			(stroke
				(width 0)
				(type default)
			)
			(fill yes)
			(layer "F.Fab")
		)
		(pad "1_2" smd circle
			(at -0.374904 0 90)
			(size 0 0)
			(layers "F.Cu" "F.Mask" "F.Paste")
			(net "P3V3_AUX")
		)
		(pad "3" smd rect
			(at -0.499872 0.999998)
			(size 0.254 0.7112)
			(layers "F.Cu" "F.Mask" "F.Paste")
			(net "GND")
		)
		(pad "4" smd rect
			(at 0 0.999998)
			(size 0.254 0.7112)
			(layers "F.Cu" "F.Mask" "F.Paste")
			(net "P3V3_SSD8_CO_ILIMIT")
		)
		(pad "5" smd rect
			(at 0.499872 0.999998)
			(size 0.254 0.7112)
			(layers "F.Cu" "F.Mask" "F.Paste")
			(net "P3V3_SSD8_CO_MODE")
		)
		(pad "6_7" smd circle
			(at 0.374904 0 270)
			(size 0 0)
			(layers "F.Cu" "F.Mask" "F.Paste")
			(net "P3V3_SSD8")
		)
		(pad "8" smd rect
			(at 0.499872 -0.999998)
			(size 0.254 0.7112)
			(layers "F.Cu" "F.Mask" "F.Paste")
			(net "P3V3_SSD8_CO_GATE")
		)
		(pad "9" smd rect
			(at 0 -0.999998)
			(size 0.254 0.7112)
			(layers "F.Cu" "F.Mask" "F.Paste")
			(net "P3V3_SSD8_CO_EN")
		)
		(pad "10" smd rect
			(at -0.499872 -0.999998)
			(size 0.254 0.7112)
			(layers "F.Cu" "F.Mask" "F.Paste")
			(net "P3V3_SSD8_CO_DV_DT")
		)
	)
	(footprint ""
		(layer "F.Cu")
		(at 241.02949 -211.266278 90)
		(property "Reference" "C196"
			(at 0 0 90)
			(layer "F.SilkS")
			(hide yes)
			(effects
				(font
					(size 1.27 1.27)
				)
			)
		)
		(property "Value" ""
			(at 0 0 90)
			(layer "F.Fab")
			(effects
				(font
					(size 1.27 1.27)
				)
			)
		)
		(duplicate_pad_numbers_are_jumpers no)
		(fp_line
			(start 0.7874 -0.4064)
			(end 0.7874 0.4064)
			(stroke
				(width 0.1524)
				(type default)
			)
			(layer "F.SilkS")
		)
		(fp_line
			(start -0.7874 -0.4064)
			(end 0.7874 -0.4064)
			(stroke
				(width 0.1524)
				(type default)
			)
			(layer "F.SilkS")
		)
		(fp_line
			(start 0.7874 0.4064)
			(end -0.7874 0.4064)
			(stroke
				(width 0.1524)
				(type default)
			)
			(layer "F.SilkS")
		)
		(fp_line
			(start -0.7874 0.4064)
			(end -0.7874 -0.4064)
			(stroke
				(width 0.1524)
				(type default)
			)
			(layer "F.SilkS")
		)
		(fp_line
			(start -0.12065 -0.305054)
			(end -0.12065 -0.2794)
			(stroke
				(width 0.1)
				(type default)
			)
			(layer "F.Fab")
		)
		(fp_line
			(start -0.67945 -0.305054)
			(end -0.12065 -0.305054)
			(stroke
				(width 0.1)
				(type default)
			)
			(layer "F.Fab")
		)
		(fp_line
			(start 0.67945 -0.3048)
			(end 0.67945 0.3048)
			(stroke
				(width 0.1)
				(type default)
			)
			(layer "F.Fab")
		)
		(fp_line
			(start 0.12065 -0.3048)
			(end 0.67945 -0.3048)
			(stroke
				(width 0.1)
				(type default)
			)
			(layer "F.Fab")
		)
		(fp_line
			(start 0.12065 -0.2794)
			(end 0.12065 -0.3048)
			(stroke
				(width 0.1)
				(type default)
			)
			(layer "F.Fab")
		)
		(fp_line
			(start -0.12065 -0.2794)
			(end 0.12065 -0.2794)
			(stroke
				(width 0.1)
				(type default)
			)
			(layer "F.Fab")
		)
		(fp_line
			(start 0.120396 0.2794)
			(end -0.12065 0.2794)
			(stroke
				(width 0.1)
				(type default)
			)
			(layer "F.Fab")
		)
		(fp_line
			(start -0.12065 0.2794)
			(end -0.12065 0.3048)
			(stroke
				(width 0.1)
				(type default)
			)
			(layer "F.Fab")
		)
		(fp_line
			(start 0.67945 0.3048)
			(end 0.120396 0.3048)
			(stroke
				(width 0.1)
				(type default)
			)
			(layer "F.Fab")
		)
		(fp_line
			(start 0.120396 0.3048)
			(end 0.120396 0.2794)
			(stroke
				(width 0.1)
				(type default)
			)
			(layer "F.Fab")
		)
		(fp_line
			(start -0.12065 0.3048)
			(end -0.67945 0.3048)
			(stroke
				(width 0.1)
				(type default)
			)
			(layer "F.Fab")
		)
		(fp_line
			(start -0.67945 0.3048)
			(end -0.67945 -0.305054)
			(stroke
				(width 0.1)
				(type default)
			)
			(layer "F.Fab")
		)
		(pad "1" smd circle
			(at -0.40005 0 90)
			(size 0 0)
			(layers "F.Cu" "F.Mask" "F.Paste")
			(net "P3V3_SCALED")
		)
		(pad "2" smd circle
			(at 0.40005 0 90)
			(size 0 0)
			(layers "F.Cu" "F.Mask" "F.Paste")
			(net "GND")
		)
	)
	(footprint ""
		(layer "F.Cu")
		(at 336.042 -155.702 180)
		(property "Reference" "R4801"
			(at 0 0 180)
			(layer "F.SilkS")
			(hide yes)
			(effects
				(font
					(size 1.27 1.27)
				)
			)
		)
		(property "Value" ""
			(at 0 0 180)
			(layer "F.Fab")
			(effects
				(font
					(size 1.27 1.27)
				)
			)
		)
		(duplicate_pad_numbers_are_jumpers no)
		(fp_line
			(start 0.7874 0.4064)
			(end -0.7874 0.4064)
			(stroke
				(width 0.1524)
				(type default)
			)
			(layer "F.SilkS")
		)
		(fp_line
			(start 0.7874 -0.4064)
			(end 0.7874 0.4064)
			(stroke
				(width 0.1524)
				(type default)
			)
			(layer "F.SilkS")
		)
		(fp_line
			(start -0.7874 0.4064)
			(end -0.7874 -0.4064)
			(stroke
				(width 0.1524)
				(type default)
			)
			(layer "F.SilkS")
		)
		(fp_line
			(start -0.7874 -0.4064)
			(end 0.7874 -0.4064)
			(stroke
				(width 0.1524)
				(type default)
			)
			(layer "F.SilkS")
		)
		(fp_line
			(start 0.67945 0.3048)
			(end 0.120396 0.3048)
			(stroke
				(width 0.1)
				(type default)
			)
			(layer "F.Fab")
		)
		(fp_line
			(start 0.67945 -0.3048)
			(end 0.67945 0.3048)
			(stroke
				(width 0.1)
				(type default)
			)
			(layer "F.Fab")
		)
		(fp_line
			(start 0.12065 -0.2794)
			(end 0.12065 -0.3048)
			(stroke
				(width 0.1)
				(type default)
			)
			(layer "F.Fab")
		)
		(fp_line
			(start 0.12065 -0.3048)
			(end 0.67945 -0.3048)
			(stroke
				(width 0.1)
				(type default)
			)
			(layer "F.Fab")
		)
		(fp_line
			(start 0.120396 0.3048)
			(end 0.120396 0.2794)
			(stroke
				(width 0.1)
				(type default)
			)
			(layer "F.Fab")
		)
		(fp_line
			(start 0.120396 0.2794)
			(end -0.12065 0.2794)
			(stroke
				(width 0.1)
				(type default)
			)
			(layer "F.Fab")
		)
		(fp_line
			(start -0.12065 0.3048)
			(end -0.67945 0.3048)
			(stroke
				(width 0.1)
				(type default)
			)
			(layer "F.Fab")
		)
		(fp_line
			(start -0.12065 0.2794)
			(end -0.12065 0.3048)
			(stroke
				(width 0.1)
				(type default)
			)
			(layer "F.Fab")
		)
		(fp_line
			(start -0.12065 -0.2794)
			(end 0.12065 -0.2794)
			(stroke
				(width 0.1)
				(type default)
			)
			(layer "F.Fab")
		)
		(fp_line
			(start -0.12065 -0.305054)
			(end -0.12065 -0.2794)
			(stroke
				(width 0.1)
				(type default)
			)
			(layer "F.Fab")
		)
		(fp_line
			(start -0.67945 0.3048)
			(end -0.67945 -0.305054)
			(stroke
				(width 0.1)
				(type default)
			)
			(layer "F.Fab")
		)
		(fp_line
			(start -0.67945 -0.305054)
			(end -0.12065 -0.305054)
			(stroke
				(width 0.1)
				(type default)
			)
			(layer "F.Fab")
		)
		(pad "1" smd circle
			(at -0.40005 0 180)
			(size 0 0)
			(layers "F.Cu" "F.Mask" "F.Paste")
			(net "SSD13_PEX_PWR_EN_R")
		)
		(pad "2" smd circle
			(at 0.40005 0 180)
			(size 0 0)
			(layers "F.Cu" "F.Mask" "F.Paste")
			(net "GND")
		)
	)
	(footprint ""
		(layer "F.Cu")
		(at 295.852342 -356.244906 90)
		(property "Reference" "C585"
			(at 0 0 90)
			(layer "F.SilkS")
			(hide yes)
			(effects
				(font
					(size 1.27 1.27)
				)
			)
		)
		(property "Value" ""
			(at 0 0 90)
			(layer "F.Fab")
			(effects
				(font
					(size 1.27 1.27)
				)
			)
		)
		(duplicate_pad_numbers_are_jumpers no)
		(fp_line
			(start 0.299974 -0.150114)
			(end 0.299974 0.150114)
			(stroke
				(width 0.1)
				(type default)
			)
			(layer "F.Fab")
		)
		(fp_line
			(start -0.299974 -0.150114)
			(end 0.299974 -0.150114)
			(stroke
				(width 0.1)
				(type default)
			)
			(layer "F.Fab")
		)
		(fp_line
			(start 0.299974 0.150114)
			(end -0.299974 0.150114)
			(stroke
				(width 0.1)
				(type default)
			)
			(layer "F.Fab")
		)
		(fp_line
			(start -0.299974 0.150114)
			(end -0.299974 -0.150114)
			(stroke
				(width 0.1)
				(type default)
			)
			(layer "F.Fab")
		)
		(pad "1" smd rect
			(at -0.2667 0 90)
			(size 0.3048 0.381)
			(layers "F.Cu" "F.Mask" "F.Paste")
			(net "P5E_PEX2_STN7_TX_DP<126>")
		)
		(pad "2" smd rect
			(at 0.2667 0 90)
			(size 0.3048 0.381)
			(layers "F.Cu" "F.Mask" "F.Paste")
			(net "P5E_PEX2_STN7_TX_C_DP<126>")
		)
	)
	(footprint ""
		(layer "F.Cu")
		(at 445.771524 -25.342342 -90)
		(property "Reference" "R454"
			(at 0 0 270)
			(layer "F.SilkS")
			(hide yes)
			(effects
				(font
					(size 1.27 1.27)
				)
			)
		)
		(property "Value" ""
			(at 0 0 270)
			(layer "F.Fab")
			(effects
				(font
					(size 1.27 1.27)
				)
			)
		)
		(duplicate_pad_numbers_are_jumpers no)
		(fp_line
			(start -0.7874 0.4064)
			(end -0.7874 -0.4064)
			(stroke
				(width 0.1524)
				(type default)
			)
			(layer "F.SilkS")
		)
		(fp_line
			(start 0.7874 0.4064)
			(end -0.7874 0.4064)
			(stroke
				(width 0.1524)
				(type default)
			)
			(layer "F.SilkS")
		)
		(fp_line
			(start -0.7874 -0.4064)
			(end 0.7874 -0.4064)
			(stroke
				(width 0.1524)
				(type default)
			)
			(layer "F.SilkS")
		)
		(fp_line
			(start 0.7874 -0.4064)
			(end 0.7874 0.4064)
			(stroke
				(width 0.1524)
				(type default)
			)
			(layer "F.SilkS")
		)
		(fp_line
			(start -0.67945 0.3048)
			(end -0.67945 -0.305054)
			(stroke
				(width 0.1)
				(type default)
			)
			(layer "F.Fab")
		)
		(fp_line
			(start -0.12065 0.3048)
			(end -0.67945 0.3048)
			(stroke
				(width 0.1)
				(type default)
			)
			(layer "F.Fab")
		)
		(fp_line
			(start 0.120396 0.3048)
			(end 0.120396 0.2794)
			(stroke
				(width 0.1)
				(type default)
			)
			(layer "F.Fab")
		)
		(fp_line
			(start 0.67945 0.3048)
			(end 0.120396 0.3048)
			(stroke
				(width 0.1)
				(type default)
			)
			(layer "F.Fab")
		)
		(fp_line
			(start -0.12065 0.2794)
			(end -0.12065 0.3048)
			(stroke
				(width 0.1)
				(type default)
			)
			(layer "F.Fab")
		)
		(fp_line
			(start 0.120396 0.2794)
			(end -0.12065 0.2794)
			(stroke
				(width 0.1)
				(type default)
			)
			(layer "F.Fab")
		)
		(fp_line
			(start -0.12065 -0.2794)
			(end 0.12065 -0.2794)
			(stroke
				(width 0.1)
				(type default)
			)
			(layer "F.Fab")
		)
		(fp_line
			(start 0.12065 -0.2794)
			(end 0.12065 -0.3048)
			(stroke
				(width 0.1)
				(type default)
			)
			(layer "F.Fab")
		)
		(fp_line
			(start 0.12065 -0.3048)
			(end 0.67945 -0.3048)
			(stroke
				(width 0.1)
				(type default)
			)
			(layer "F.Fab")
		)
		(fp_line
			(start 0.67945 -0.3048)
			(end 0.67945 0.3048)
			(stroke
				(width 0.1)
				(type default)
			)
			(layer "F.Fab")
		)
		(fp_line
			(start -0.67945 -0.305054)
			(end -0.12065 -0.305054)
			(stroke
				(width 0.1)
				(type default)
			)
			(layer "F.Fab")
		)
		(fp_line
			(start -0.12065 -0.305054)
			(end -0.12065 -0.2794)
			(stroke
				(width 0.1)
				(type default)
			)
			(layer "F.Fab")
		)
		(pad "1" smd circle
			(at -0.40005 0 270)
			(size 0 0)
			(layers "F.Cu" "F.Mask" "F.Paste")
			(net "P3V3_SSD15")
		)
		(pad "2" smd circle
			(at 0.40005 0 270)
			(size 0 0)
			(layers "F.Cu" "F.Mask" "F.Paste")
			(net "DUALPORT_N_SSD15")
		)
	)
	(footprint ""
		(layer "F.Cu")
		(at 58.405268 -393.16279 -90)
		(property "Reference" "C4017"
			(at 0 0 270)
			(layer "F.SilkS")
			(hide yes)
			(effects
				(font
					(size 1.27 1.27)
				)
			)
		)
		(property "Value" ""
			(at 0 0 270)
			(layer "F.Fab")
			(effects
				(font
					(size 1.27 1.27)
				)
			)
		)
		(duplicate_pad_numbers_are_jumpers no)
		(fp_line
			(start -0.7874 0.4064)
			(end -0.7874 -0.4064)
			(stroke
				(width 0.1524)
				(type default)
			)
			(layer "F.SilkS")
		)
		(fp_line
			(start 0.7874 0.4064)
			(end -0.7874 0.4064)
			(stroke
				(width 0.1524)
				(type default)
			)
			(layer "F.SilkS")
		)
		(fp_line
			(start -0.7874 -0.4064)
			(end 0.7874 -0.4064)
			(stroke
				(width 0.1524)
				(type default)
			)
			(layer "F.SilkS")
		)
		(fp_line
			(start 0.7874 -0.4064)
			(end 0.7874 0.4064)
			(stroke
				(width 0.1524)
				(type default)
			)
			(layer "F.SilkS")
		)
		(fp_line
			(start -0.67945 0.3048)
			(end -0.67945 -0.305054)
			(stroke
				(width 0.1)
				(type default)
			)
			(layer "F.Fab")
		)
		(fp_line
			(start -0.12065 0.3048)
			(end -0.67945 0.3048)
			(stroke
				(width 0.1)
				(type default)
			)
			(layer "F.Fab")
		)
		(fp_line
			(start 0.120396 0.3048)
			(end 0.120396 0.2794)
			(stroke
				(width 0.1)
				(type default)
			)
			(layer "F.Fab")
		)
		(fp_line
			(start 0.67945 0.3048)
			(end 0.120396 0.3048)
			(stroke
				(width 0.1)
				(type default)
			)
			(layer "F.Fab")
		)
		(fp_line
			(start -0.12065 0.2794)
			(end -0.12065 0.3048)
			(stroke
				(width 0.1)
				(type default)
			)
			(layer "F.Fab")
		)
		(fp_line
			(start 0.120396 0.2794)
			(end -0.12065 0.2794)
			(stroke
				(width 0.1)
				(type default)
			)
			(layer "F.Fab")
		)
		(fp_line
			(start -0.12065 -0.2794)
			(end 0.12065 -0.2794)
			(stroke
				(width 0.1)
				(type default)
			)
			(layer "F.Fab")
		)
		(fp_line
			(start 0.12065 -0.2794)
			(end 0.12065 -0.3048)
			(stroke
				(width 0.1)
				(type default)
			)
			(layer "F.Fab")
		)
		(fp_line
			(start 0.12065 -0.3048)
			(end 0.67945 -0.3048)
			(stroke
				(width 0.1)
				(type default)
			)
			(layer "F.Fab")
		)
		(fp_line
			(start 0.67945 -0.3048)
			(end 0.67945 0.3048)
			(stroke
				(width 0.1)
				(type default)
			)
			(layer "F.Fab")
		)
		(fp_line
			(start -0.67945 -0.305054)
			(end -0.12065 -0.305054)
			(stroke
				(width 0.1)
				(type default)
			)
			(layer "F.Fab")
		)
		(fp_line
			(start -0.12065 -0.305054)
			(end -0.12065 -0.2794)
			(stroke
				(width 0.1)
				(type default)
			)
			(layer "F.Fab")
		)
		(pad "1" smd circle
			(at -0.40005 0 270)
			(size 0 0)
			(layers "F.Cu" "F.Mask" "F.Paste")
			(net "GND")
		)
		(pad "2" smd circle
			(at 0.40005 0 270)
			(size 0 0)
			(layers "F.Cu" "F.Mask" "F.Paste")
			(net "GPU_THERM_OVERT_N")
		)
	)
	(footprint ""
		(layer "F.Cu")
		(at 49.667922 -18.437098)
		(property "Reference" "R1638"
			(at 0 0 0)
			(layer "F.SilkS")
			(hide yes)
			(effects
				(font
					(size 1.27 1.27)
				)
			)
		)
		(property "Value" ""
			(at 0 0 0)
			(layer "F.Fab")
			(effects
				(font
					(size 1.27 1.27)
				)
			)
		)
		(duplicate_pad_numbers_are_jumpers no)
		(fp_line
			(start -0.7874 -0.4064)
			(end 0.7874 -0.4064)
			(stroke
				(width 0.1524)
				(type default)
			)
			(layer "F.SilkS")
		)
		(fp_line
			(start -0.7874 0.4064)
			(end -0.7874 -0.4064)
			(stroke
				(width 0.1524)
				(type default)
			)
			(layer "F.SilkS")
		)
		(fp_line
			(start 0.7874 -0.4064)
			(end 0.7874 0.4064)
			(stroke
				(width 0.1524)
				(type default)
			)
			(layer "F.SilkS")
		)
		(fp_line
			(start 0.7874 0.4064)
			(end -0.7874 0.4064)
			(stroke
				(width 0.1524)
				(type default)
			)
			(layer "F.SilkS")
		)
		(fp_line
			(start -0.67945 -0.305054)
			(end -0.12065 -0.305054)
			(stroke
				(width 0.1)
				(type default)
			)
			(layer "F.Fab")
		)
		(fp_line
			(start -0.67945 0.3048)
			(end -0.67945 -0.305054)
			(stroke
				(width 0.1)
				(type default)
			)
			(layer "F.Fab")
		)
		(fp_line
			(start -0.12065 -0.305054)
			(end -0.12065 -0.2794)
			(stroke
				(width 0.1)
				(type default)
			)
			(layer "F.Fab")
		)
		(fp_line
			(start -0.12065 -0.2794)
			(end 0.12065 -0.2794)
			(stroke
				(width 0.1)
				(type default)
			)
			(layer "F.Fab")
		)
		(fp_line
			(start -0.12065 0.2794)
			(end -0.12065 0.3048)
			(stroke
				(width 0.1)
				(type default)
			)
			(layer "F.Fab")
		)
		(fp_line
			(start -0.12065 0.3048)
			(end -0.67945 0.3048)
			(stroke
				(width 0.1)
				(type default)
			)
			(layer "F.Fab")
		)
		(fp_line
			(start 0.120396 0.2794)
			(end -0.12065 0.2794)
			(stroke
				(width 0.1)
				(type default)
			)
			(layer "F.Fab")
		)
		(fp_line
			(start 0.120396 0.3048)
			(end 0.120396 0.2794)
			(stroke
				(width 0.1)
				(type default)
			)
			(layer "F.Fab")
		)
		(fp_line
			(start 0.12065 -0.3048)
			(end 0.67945 -0.3048)
			(stroke
				(width 0.1)
				(type default)
			)
			(layer "F.Fab")
		)
		(fp_line
			(start 0.12065 -0.2794)
			(end 0.12065 -0.3048)
			(stroke
				(width 0.1)
				(type default)
			)
			(layer "F.Fab")
		)
		(fp_line
			(start 0.67945 -0.3048)
			(end 0.67945 0.3048)
			(stroke
				(width 0.1)
				(type default)
			)
			(layer "F.Fab")
		)
		(fp_line
			(start 0.67945 0.3048)
			(end 0.120396 0.3048)
			(stroke
				(width 0.1)
				(type default)
			)
			(layer "F.Fab")
		)
		(pad "1" smd circle
			(at -0.40005 0)
			(size 0 0)
			(layers "F.Cu" "F.Mask" "F.Paste")
			(net "SMB_ISO_SSD1_R_SCL")
		)
		(pad "2" smd circle
			(at 0.40005 0)
			(size 0 0)
			(layers "F.Cu" "F.Mask" "F.Paste")
			(net "SMB_ISO_SSD1_SCL")
		)
	)
)
